(kicad_pcb
	(version 20260206)
	(generator "pcbnew")
	(generator_version "10.0")
	(general
		(thickness 1.6)
		(legacy_teardrops no)
	)
	(paper "A4")
	(title_block
		(title "Bryce Canyon_SCC_16316-1_OCP.brd")
		(comment 1 "Bryce Canyon / footprints 1505-1512 of 1561")
	)
	(layers
		(0 "F.Cu" signal "TOP")
		(4 "In1.Cu" signal "L2GND")
		(6 "In2.Cu" signal "L3")
		(8 "In3.Cu" signal "L4VCC")
		(10 "In4.Cu" signal "L5VCC")
		(12 "In5.Cu" signal "L6")
		(14 "In6.Cu" signal "L7GND")
		(2 "B.Cu" signal "BOTTOM")
		(9 "F.Adhes" user "F.Adhesive")
		(11 "B.Adhes" user "B.Adhesive")
		(13 "F.Paste" user "Package Geometry/Pastemask Top")
		(15 "B.Paste" user "Package Geometry/Pastemask Bottom")
		(5 "F.SilkS" user "Ref Des/Silkscreen Top")
		(7 "B.SilkS" user "Ref Des/Silkscreen Bottom")
		(1 "F.Mask" user "Board Geometry/Soldermask Top")
		(3 "B.Mask" user "Board Geometry/Soldermask Bottom")
		(17 "Dwgs.User" user "User.Drawings")
		(19 "Cmts.User" user "User.Comments")
		(21 "Eco1.User" user "User.Eco1")
		(23 "Eco2.User" user "User.Eco2")
		(25 "Edge.Cuts" user "Board Geometry/Outline")
		(27 "Margin" user)
		(31 "F.CrtYd" user "Package Geometry/Place Bound Top")
		(29 "B.CrtYd" user "Package Geometry/Place Bound Bottom")
		(35 "F.Fab" user "Ref Des/Assembly Top")
		(33 "B.Fab" user "Ref Des/Assembly Bottom")
	)
	(footprint ""
		(layer "B.Cu")
		(at 182.8038 -54.9402)
		(property "Reference" "R218"
			(at 0 0 0)
			(layer "B.SilkS")
			(hide yes)
			(effects
				(font
					(size 1.27 1.27)
				)
				(justify mirror)
			)
		)
		(property "Value" "10KR2F-2-GP"
			(at -0.064008 -3.993896 0)
			(unlocked yes)
			(layer "B.Fab")
			(hide yes)
			(effects
				(font
					(size 1.016 1.016)
					(thickness 0.1524)
				)
				(justify mirror)
			)
		)
		(property "Device Type" "R402H16"
			(at -0.064008 -5.517896 0)
			(unlocked yes)
			(layer "B.Fab")
			(hide yes)
			(effects
				(font
					(size 1.016 1.016)
					(thickness 0.1524)
				)
				(justify mirror)
			)
		)
		(duplicate_pad_numbers_are_jumpers no)
		(fp_line
			(start -0.508 -0.9398)
			(end 0.508 -0.9398)
			(stroke
				(width 0.1524)
				(type default)
			)
			(layer "B.SilkS")
		)
		(fp_line
			(start 0.508 -0.9398)
			(end 0.508 0.9398)
			(stroke
				(width 0.1524)
				(type default)
			)
			(layer "B.SilkS")
		)
		(fp_rect
			(start 0.508 0.9398)
			(end -0.508 -0.9398)
			(stroke
				(width 0)
				(type default)
			)
			(fill no)
			(layer "B.CrtYd")
		)
		(fp_rect
			(start 0.508 0.9398)
			(end -0.508 -0.9398)
			(stroke
				(width 0)
				(type default)
			)
			(fill no)
			(layer "B.Fab")
		)
		(pad "1" smd custom
			(at 0 -0.4445 180)
			(size 0.1397 0.1397)
			(layers "B.Cu" "B.Mask" "B.Paste")
			(net "P1V8_C")
			(options
				(clearance outline)
				(anchor circle)
			)
			(primitives
				(gr_poly
					(pts
						(arc
							(start -0.1778 0.2794)
							(mid -0.249642 0.249642)
							(end -0.2794 0.1778)
						)
						(arc
							(start -0.2794 -0.1778)
							(mid -0.249642 -0.249642)
							(end -0.1778 -0.2794)
						)
						(arc
							(start 0.1778 -0.2794)
							(mid 0.249642 -0.249642)
							(end 0.2794 -0.1778)
						)
						(arc
							(start 0.2794 0.1778)
							(mid 0.249642 0.249642)
							(end 0.1778 0.2794)
						)
					)
					(width 0)
					(fill yes)
				)
			)
		)
		(pad "2" smd custom
			(at 0 0.4445 180)
			(size 0.1397 0.1397)
			(layers "B.Cu" "B.Mask" "B.Paste")
			(net "XM_WE_N")
			(options
				(clearance outline)
				(anchor circle)
			)
			(primitives
				(gr_poly
					(pts
						(arc
							(start -0.1778 0.2794)
							(mid -0.249642 0.249642)
							(end -0.2794 0.1778)
						)
						(arc
							(start -0.2794 -0.1778)
							(mid -0.249642 -0.249642)
							(end -0.1778 -0.2794)
						)
						(arc
							(start 0.1778 -0.2794)
							(mid 0.249642 -0.249642)
							(end 0.2794 -0.1778)
						)
						(arc
							(start 0.2794 0.1778)
							(mid 0.249642 0.249642)
							(end 0.1778 0.2794)
						)
					)
					(width 0)
					(fill yes)
				)
			)
		)
	)
	(footprint ""
		(layer "B.Cu")
		(at 177.8127 -38.11016 90)
		(property "Reference" "C434"
			(at 0 0 90)
			(layer "B.SilkS")
			(hide yes)
			(effects
				(font
					(size 1.27 1.27)
				)
				(justify mirror)
			)
		)
		(property "Value" "SCD1U6D3V1KX-GP"
			(at 2.8321 -1.7399 90)
			(unlocked yes)
			(layer "B.Fab")
			(hide yes)
			(effects
				(font
					(size 1.016 1.016)
					(thickness 0.1524)
				)
				(justify mirror)
			)
		)
		(property "Device Type" "C0201H13"
			(at 2.8321 -3.2639 90)
			(unlocked yes)
			(layer "B.Fab")
			(hide yes)
			(effects
				(font
					(size 1.016 1.016)
					(thickness 0.1524)
				)
				(justify mirror)
			)
		)
		(duplicate_pad_numbers_are_jumpers no)
		(fp_rect
			(start 0.2794 0.6477)
			(end -0.2794 -0.6477)
			(stroke
				(width 0)
				(type default)
			)
			(fill no)
			(layer "B.CrtYd")
		)
		(fp_rect
			(start 0.2794 0.6477)
			(end -0.2794 -0.6477)
			(stroke
				(width 0)
				(type default)
			)
			(fill no)
			(layer "B.Fab")
		)
		(pad "1" smd custom
			(at 0 -0.2794 270)
			(size 0.0762 0.0762)
			(layers "B.Cu" "B.Mask" "B.Paste")
			(net "P0V975")
			(options
				(clearance outline)
				(anchor circle)
			)
			(primitives
				(gr_poly
					(pts
						(arc
							(start 0.1524 0.127)
							(mid 0.137521 0.162921)
							(end 0.1016 0.1778)
						)
						(arc
							(start -0.1016 0.1778)
							(mid -0.137521 0.162921)
							(end -0.1524 0.127)
						)
						(arc
							(start -0.1524 -0.127)
							(mid -0.137521 -0.162921)
							(end -0.1016 -0.1778)
						)
						(arc
							(start 0.1016 -0.1778)
							(mid 0.137521 -0.162921)
							(end 0.1524 -0.127)
						)
					)
					(width 0)
					(fill yes)
				)
			)
		)
		(pad "2" smd custom
			(at 0 0.2794 270)
			(size 0.0762 0.0762)
			(layers "B.Cu" "B.Mask" "B.Paste")
			(net "GND")
			(options
				(clearance outline)
				(anchor circle)
			)
			(primitives
				(gr_poly
					(pts
						(arc
							(start 0.1524 0.127)
							(mid 0.137521 0.162921)
							(end 0.1016 0.1778)
						)
						(arc
							(start -0.1016 0.1778)
							(mid -0.137521 0.162921)
							(end -0.1524 0.127)
						)
						(arc
							(start -0.1524 -0.127)
							(mid -0.137521 -0.162921)
							(end -0.1016 -0.1778)
						)
						(arc
							(start 0.1016 -0.1778)
							(mid 0.137521 -0.162921)
							(end 0.1524 -0.127)
						)
					)
					(width 0)
					(fill yes)
				)
			)
		)
	)
	(footprint ""
		(layer "B.Cu")
		(at 163.957 -66.7766)
		(property "Reference" "R281"
			(at 0 0 0)
			(layer "B.SilkS")
			(hide yes)
			(effects
				(font
					(size 1.27 1.27)
				)
				(justify mirror)
			)
		)
		(property "Value" "10R2F-L-GP"
			(at -0.064008 -3.993896 0)
			(unlocked yes)
			(layer "B.Fab")
			(hide yes)
			(effects
				(font
					(size 1.016 1.016)
					(thickness 0.1524)
				)
				(justify mirror)
			)
		)
		(property "Device Type" "R402H14"
			(at -0.064008 -5.517896 0)
			(unlocked yes)
			(layer "B.Fab")
			(hide yes)
			(effects
				(font
					(size 1.016 1.016)
					(thickness 0.1524)
				)
				(justify mirror)
			)
		)
		(duplicate_pad_numbers_are_jumpers no)
		(fp_line
			(start -0.508 -0.9398)
			(end 0.508 -0.9398)
			(stroke
				(width 0.1524)
				(type default)
			)
			(layer "B.SilkS")
		)
		(fp_line
			(start 0.508 -0.9398)
			(end 0.508 0.9398)
			(stroke
				(width 0.1524)
				(type default)
			)
			(layer "B.SilkS")
		)
		(fp_rect
			(start 0.508 0.9398)
			(end -0.508 -0.9398)
			(stroke
				(width 0)
				(type default)
			)
			(fill no)
			(layer "B.CrtYd")
		)
		(fp_rect
			(start 0.508 0.9398)
			(end -0.508 -0.9398)
			(stroke
				(width 0)
				(type default)
			)
			(fill no)
			(layer "B.Fab")
		)
		(pad "1" smd custom
			(at 0 -0.4445 180)
			(size 0.1397 0.1397)
			(layers "B.Cu" "B.Mask" "B.Paste")
			(net "P1V8_C")
			(options
				(clearance outline)
				(anchor circle)
			)
			(primitives
				(gr_poly
					(pts
						(arc
							(start -0.1778 0.2794)
							(mid -0.249642 0.249642)
							(end -0.2794 0.1778)
						)
						(arc
							(start -0.2794 -0.1778)
							(mid -0.249642 -0.249642)
							(end -0.1778 -0.2794)
						)
						(arc
							(start 0.1778 -0.2794)
							(mid 0.249642 -0.249642)
							(end 0.2794 -0.1778)
						)
						(arc
							(start 0.2794 0.1778)
							(mid 0.249642 0.249642)
							(end 0.1778 0.2794)
						)
					)
					(width 0)
					(fill yes)
				)
			)
		)
		(pad "2" smd custom
			(at 0 0.4445 180)
			(size 0.1397 0.1397)
			(layers "B.Cu" "B.Mask" "B.Paste")
			(net "VDDA_SAS_REF_CLK")
			(options
				(clearance outline)
				(anchor circle)
			)
			(primitives
				(gr_poly
					(pts
						(arc
							(start -0.1778 0.2794)
							(mid -0.249642 0.249642)
							(end -0.2794 0.1778)
						)
						(arc
							(start -0.2794 -0.1778)
							(mid -0.249642 -0.249642)
							(end -0.1778 -0.2794)
						)
						(arc
							(start 0.1778 -0.2794)
							(mid 0.249642 -0.249642)
							(end 0.2794 -0.1778)
						)
						(arc
							(start 0.2794 0.1778)
							(mid 0.249642 0.249642)
							(end 0.1778 0.2794)
						)
					)
					(width 0)
					(fill yes)
				)
			)
		)
	)
	(footprint ""
		(layer "B.Cu")
		(at 158.821374 -33.403032 180)
		(property "Reference" "C372"
			(at 0 0 0)
			(layer "B.SilkS")
			(hide yes)
			(effects
				(font
					(size 1.27 1.27)
				)
				(justify mirror)
			)
		)
		(property "Value" "SC10U6D3V5KX-4GP"
			(at 0.0762 -6.1214 180)
			(unlocked yes)
			(layer "B.Fab")
			(hide yes)
			(effects
				(font
					(size 1.016 1.016)
					(thickness 0.1524)
				)
				(justify mirror)
			)
		)
		(property "Device Type" "C805H58"
			(at 0.0762 -8.1534 180)
			(unlocked yes)
			(layer "B.Fab")
			(hide yes)
			(effects
				(font
					(size 1.016 1.016)
					(thickness 0.1524)
				)
				(justify mirror)
			)
		)
		(duplicate_pad_numbers_are_jumpers no)
		(fp_line
			(start -0.635 0)
			(end 0.635 0)
			(stroke
				(width 0.508)
				(type default)
			)
			(layer "B.SilkS")
		)
		(fp_rect
			(start 0.9652 1.778)
			(end -0.9652 -1.778)
			(stroke
				(width 0)
				(type default)
			)
			(fill no)
			(layer "B.CrtYd")
		)
		(fp_poly
			(pts
				(xy 0.9652 -1.778) (xy -0.9652 -1.778) (xy -0.9652 1.778) (xy 0.9652 1.778)
			)
			(stroke
				(width 0)
				(type default)
			)
			(fill no)
			(layer "B.Fab")
		)
		(pad "1" smd rect
			(at 0 -0.9652)
			(size 1.397 1.143)
			(layers "B.Cu" "B.Mask" "B.Paste")
			(net "SAS0_VDDH")
		)
		(pad "2" smd rect
			(at 0 0.9652)
			(size 1.397 1.143)
			(layers "B.Cu" "B.Mask" "B.Paste")
			(net "GND")
		)
	)
	(footprint ""
		(layer "B.Cu")
		(at 166.885874 -96.109282 180)
		(property "Reference" "R485"
			(at 0 0 0)
			(layer "B.SilkS")
			(hide yes)
			(effects
				(font
					(size 1.27 1.27)
				)
				(justify mirror)
			)
		)
		(property "Value" "69K8R2F-GP"
			(at -0.064008 -3.993896 180)
			(unlocked yes)
			(layer "B.Fab")
			(hide yes)
			(effects
				(font
					(size 1.016 1.016)
					(thickness 0.1524)
				)
				(justify mirror)
			)
		)
		(property "Device Type" "R402H16"
			(at -0.064008 -5.517896 180)
			(unlocked yes)
			(layer "B.Fab")
			(hide yes)
			(effects
				(font
					(size 1.016 1.016)
					(thickness 0.1524)
				)
				(justify mirror)
			)
		)
		(duplicate_pad_numbers_are_jumpers no)
		(fp_line
			(start 0.508 -0.9398)
			(end 0.508 0.9398)
			(stroke
				(width 0.1524)
				(type default)
			)
			(layer "B.SilkS")
		)
		(fp_line
			(start -0.508 -0.9398)
			(end 0.508 -0.9398)
			(stroke
				(width 0.1524)
				(type default)
			)
			(layer "B.SilkS")
		)
		(fp_rect
			(start 0.508 0.9398)
			(end -0.508 -0.9398)
			(stroke
				(width 0)
				(type default)
			)
			(fill no)
			(layer "B.CrtYd")
		)
		(fp_rect
			(start 0.508 0.9398)
			(end -0.508 -0.9398)
			(stroke
				(width 0)
				(type default)
			)
			(fill no)
			(layer "B.Fab")
		)
		(pad "1" smd custom
			(at 0 -0.4445)
			(size 0.1397 0.1397)
			(layers "B.Cu" "B.Mask" "B.Paste")
			(net "AGND_P0V975")
			(options
				(clearance outline)
				(anchor circle)
			)
			(primitives
				(gr_poly
					(pts
						(arc
							(start -0.1778 0.2794)
							(mid -0.249642 0.249642)
							(end -0.2794 0.1778)
						)
						(arc
							(start -0.2794 -0.1778)
							(mid -0.249642 -0.249642)
							(end -0.1778 -0.2794)
						)
						(arc
							(start 0.1778 -0.2794)
							(mid 0.249642 -0.249642)
							(end 0.2794 -0.1778)
						)
						(arc
							(start 0.2794 0.1778)
							(mid 0.249642 0.249642)
							(end 0.1778 0.2794)
						)
					)
					(width 0)
					(fill yes)
				)
			)
		)
		(pad "2" smd custom
			(at 0 0.4445)
			(size 0.1397 0.1397)
			(layers "B.Cu" "B.Mask" "B.Paste")
			(net "VT235_IRIP")
			(options
				(clearance outline)
				(anchor circle)
			)
			(primitives
				(gr_poly
					(pts
						(arc
							(start -0.1778 0.2794)
							(mid -0.249642 0.249642)
							(end -0.2794 0.1778)
						)
						(arc
							(start -0.2794 -0.1778)
							(mid -0.249642 -0.249642)
							(end -0.1778 -0.2794)
						)
						(arc
							(start 0.1778 -0.2794)
							(mid 0.249642 -0.249642)
							(end 0.2794 -0.1778)
						)
						(arc
							(start 0.2794 0.1778)
							(mid 0.249642 0.249642)
							(end 0.1778 0.2794)
						)
					)
					(width 0)
					(fill yes)
				)
			)
		)
	)
	(footprint ""
		(layer "B.Cu")
		(at 167.64 -52.07)
		(property "Reference" "R261"
			(at 0 0 0)
			(layer "B.SilkS")
			(hide yes)
			(effects
				(font
					(size 1.27 1.27)
				)
				(justify mirror)
			)
		)
		(property "Value" "4K7R2F-GP"
			(at -0.064008 -3.993896 0)
			(unlocked yes)
			(layer "B.Fab")
			(hide yes)
			(effects
				(font
					(size 1.016 1.016)
					(thickness 0.1524)
				)
				(justify mirror)
			)
		)
		(property "Device Type" "R402H16"
			(at -0.064008 -5.517896 0)
			(unlocked yes)
			(layer "B.Fab")
			(hide yes)
			(effects
				(font
					(size 1.016 1.016)
					(thickness 0.1524)
				)
				(justify mirror)
			)
		)
		(duplicate_pad_numbers_are_jumpers no)
		(fp_line
			(start -0.508 -0.9398)
			(end 0.508 -0.9398)
			(stroke
				(width 0.1524)
				(type default)
			)
			(layer "B.SilkS")
		)
		(fp_line
			(start 0.508 -0.9398)
			(end 0.508 0.9398)
			(stroke
				(width 0.1524)
				(type default)
			)
			(layer "B.SilkS")
		)
		(fp_rect
			(start 0.508 0.9398)
			(end -0.508 -0.9398)
			(stroke
				(width 0)
				(type default)
			)
			(fill no)
			(layer "B.CrtYd")
		)
		(fp_rect
			(start 0.508 0.9398)
			(end -0.508 -0.9398)
			(stroke
				(width 0)
				(type default)
			)
			(fill no)
			(layer "B.Fab")
		)
		(pad "1" smd custom
			(at 0 -0.4445 180)
			(size 0.1397 0.1397)
			(layers "B.Cu" "B.Mask" "B.Paste")
			(net "P1V8_C")
			(options
				(clearance outline)
				(anchor circle)
			)
			(primitives
				(gr_poly
					(pts
						(arc
							(start -0.1778 0.2794)
							(mid -0.249642 0.249642)
							(end -0.2794 0.1778)
						)
						(arc
							(start -0.2794 -0.1778)
							(mid -0.249642 -0.249642)
							(end -0.1778 -0.2794)
						)
						(arc
							(start 0.1778 -0.2794)
							(mid 0.249642 -0.249642)
							(end 0.2794 -0.1778)
						)
						(arc
							(start 0.2794 0.1778)
							(mid 0.249642 0.249642)
							(end 0.1778 0.2794)
						)
					)
					(width 0)
					(fill yes)
				)
			)
		)
		(pad "2" smd custom
			(at 0 0.4445 180)
			(size 0.1397 0.1397)
			(layers "B.Cu" "B.Mask" "B.Paste")
			(net "ICE1_TDI")
			(options
				(clearance outline)
				(anchor circle)
			)
			(primitives
				(gr_poly
					(pts
						(arc
							(start -0.1778 0.2794)
							(mid -0.249642 0.249642)
							(end -0.2794 0.1778)
						)
						(arc
							(start -0.2794 -0.1778)
							(mid -0.249642 -0.249642)
							(end -0.1778 -0.2794)
						)
						(arc
							(start 0.1778 -0.2794)
							(mid 0.249642 -0.249642)
							(end 0.2794 -0.1778)
						)
						(arc
							(start 0.2794 0.1778)
							(mid 0.249642 0.249642)
							(end 0.1778 0.2794)
						)
					)
					(width 0)
					(fill yes)
				)
			)
		)
	)
	(footprint ""
		(layer "B.Cu")
		(at 193.26098 -21.8694 90)
		(property "Reference" "R241"
			(at 0 0 90)
			(layer "B.SilkS")
			(hide yes)
			(effects
				(font
					(size 1.27 1.27)
				)
				(justify mirror)
			)
		)
		(property "Value" "10KR2F-2-GP"
			(at -0.064008 -3.993896 90)
			(unlocked yes)
			(layer "B.Fab")
			(hide yes)
			(effects
				(font
					(size 1.016 1.016)
					(thickness 0.1524)
				)
				(justify mirror)
			)
		)
		(property "Device Type" "R402H16"
			(at -0.064008 -5.517896 90)
			(unlocked yes)
			(layer "B.Fab")
			(hide yes)
			(effects
				(font
					(size 1.016 1.016)
					(thickness 0.1524)
				)
				(justify mirror)
			)
		)
		(duplicate_pad_numbers_are_jumpers no)
		(fp_line
			(start 0.508 -0.9398)
			(end 0.508 0.9398)
			(stroke
				(width 0.1524)
				(type default)
			)
			(layer "B.SilkS")
		)
		(fp_line
			(start -0.508 -0.9398)
			(end 0.508 -0.9398)
			(stroke
				(width 0.1524)
				(type default)
			)
			(layer "B.SilkS")
		)
		(fp_rect
			(start 0.508 0.9398)
			(end -0.508 -0.9398)
			(stroke
				(width 0)
				(type default)
			)
			(fill no)
			(layer "B.CrtYd")
		)
		(fp_rect
			(start 0.508 0.9398)
			(end -0.508 -0.9398)
			(stroke
				(width 0)
				(type default)
			)
			(fill no)
			(layer "B.Fab")
		)
		(pad "1" smd custom
			(at 0 -0.4445 270)
			(size 0.1397 0.1397)
			(layers "B.Cu" "B.Mask" "B.Paste")
			(net "P1V8_C")
			(options
				(clearance outline)
				(anchor circle)
			)
			(primitives
				(gr_poly
					(pts
						(arc
							(start -0.1778 0.2794)
							(mid -0.249642 0.249642)
							(end -0.2794 0.1778)
						)
						(arc
							(start -0.2794 -0.1778)
							(mid -0.249642 -0.249642)
							(end -0.1778 -0.2794)
						)
						(arc
							(start 0.1778 -0.2794)
							(mid 0.249642 -0.249642)
							(end 0.2794 -0.1778)
						)
						(arc
							(start 0.2794 0.1778)
							(mid 0.249642 0.249642)
							(end 0.1778 0.2794)
						)
					)
					(width 0)
					(fill yes)
				)
			)
		)
		(pad "2" smd custom
			(at 0 0.4445 270)
			(size 0.1397 0.1397)
			(layers "B.Cu" "B.Mask" "B.Paste")
			(net "SYS_HB_LED")
			(options
				(clearance outline)
				(anchor circle)
			)
			(primitives
				(gr_poly
					(pts
						(arc
							(start -0.1778 0.2794)
							(mid -0.249642 0.249642)
							(end -0.2794 0.1778)
						)
						(arc
							(start -0.2794 -0.1778)
							(mid -0.249642 -0.249642)
							(end -0.1778 -0.2794)
						)
						(arc
							(start 0.1778 -0.2794)
							(mid 0.249642 -0.249642)
							(end 0.2794 -0.1778)
						)
						(arc
							(start 0.2794 0.1778)
							(mid 0.249642 0.249642)
							(end 0.1778 0.2794)
						)
					)
					(width 0)
					(fill yes)
				)
			)
		)
	)
	(footprint ""
		(layer "B.Cu")
		(at 124.2822 -66.5353 -90)
		(property "Reference" "C307"
			(at 0 0 90)
			(layer "B.SilkS")
			(hide yes)
			(effects
				(font
					(size 1.27 1.27)
				)
				(justify mirror)
			)
		)
		(property "Value" "SCD1U6D3V1KX-GP"
			(at 2.8321 -1.7399 270)
			(unlocked yes)
			(layer "B.Fab")
			(hide yes)
			(effects
				(font
					(size 1.016 1.016)
					(thickness 0.1524)
				)
				(justify mirror)
			)
		)
		(property "Device Type" "C0201H13"
			(at 2.8321 -3.2639 270)
			(unlocked yes)
			(layer "B.Fab")
			(hide yes)
			(effects
				(font
					(size 1.016 1.016)
					(thickness 0.1524)
				)
				(justify mirror)
			)
		)
		(duplicate_pad_numbers_are_jumpers no)
		(fp_rect
			(start 0.2794 0.6477)
			(end -0.2794 -0.6477)
			(stroke
				(width 0)
				(type default)
			)
			(fill no)
			(layer "B.CrtYd")
		)
		(fp_rect
			(start 0.2794 0.6477)
			(end -0.2794 -0.6477)
			(stroke
				(width 0)
				(type default)
			)
			(fill no)
			(layer "B.Fab")
		)
		(pad "1" smd custom
			(at 0 -0.2794 90)
			(size 0.0762 0.0762)
			(layers "B.Cu" "B.Mask" "B.Paste")
			(net "GB_VDDA")
			(options
				(clearance outline)
				(anchor circle)
			)
			(primitives
				(gr_poly
					(pts
						(arc
							(start 0.1524 0.127)
							(mid 0.137521 0.162921)
							(end 0.1016 0.1778)
						)
						(arc
							(start -0.1016 0.1778)
							(mid -0.137521 0.162921)
							(end -0.1524 0.127)
						)
						(arc
							(start -0.1524 -0.127)
							(mid -0.137521 -0.162921)
							(end -0.1016 -0.1778)
						)
						(arc
							(start 0.1016 -0.1778)
							(mid 0.137521 -0.162921)
							(end 0.1524 -0.127)
						)
					)
					(width 0)
					(fill yes)
				)
			)
		)
		(pad "2" smd custom
			(at 0 0.2794 90)
			(size 0.0762 0.0762)
			(layers "B.Cu" "B.Mask" "B.Paste")
			(net "GND")
			(options
				(clearance outline)
				(anchor circle)
			)
			(primitives
				(gr_poly
					(pts
						(arc
							(start 0.1524 0.127)
							(mid 0.137521 0.162921)
							(end 0.1016 0.1778)
						)
						(arc
							(start -0.1016 0.1778)
							(mid -0.137521 0.162921)
							(end -0.1524 0.127)
						)
						(arc
							(start -0.1524 -0.127)
							(mid -0.137521 -0.162921)
							(end -0.1016 -0.1778)
						)
						(arc
							(start 0.1016 -0.1778)
							(mid 0.137521 -0.162921)
							(end 0.1524 -0.127)
						)
					)
					(width 0)
					(fill yes)
				)
			)
		)
	)
)
